# TIMECARD (Time Appliance Project (Time Card)) — schematic netlist excerpt (pin names and nets, part order shuffled) for the footprints in the layout excerpt that follows; sources: Cadence DE-HDL packaged netlist, KiCad conversion of R4006-B0001-02_R01.brd

R460  RESISTOR  1KOHM 1%  pkg SMC_0402R_H016  page 24 : \1\ = FT_USB_DETECT ; \2\ = UNNAMED_524_FT4232HLREELQFP64_7
R257  RESISTOR  330OHM 1%  pkg SMC_0402R_H016  page 26 : \1\ = UNNAMED_14_OPTICAL_I12_A ; \2\ = XP3R3V_FPGA

(kicad_pcb
	(version 20260206)
	(generator "pcbnew")
	(generator_version "10.0")
	(general
		(thickness 1.6)
		(legacy_teardrops no)
	)
	(paper "A4")
	(title_block
		(title "timecard-production-celestica-r4006 — R4006-B0001-02_R01.brd")
		(comment 1 "Time Appliance Project (Time Card) / footprints 924-925 of 1113")
	)
	(layers
		(0 "F.Cu" signal "TOP")
		(4 "In1.Cu" signal "L02_GND1")
		(6 "In2.Cu" signal "L03_SIG1")
		(8 "In3.Cu" signal "L04_GND2")
		(10 "In4.Cu" signal "L05_VCC1")
		(12 "In5.Cu" signal "L06_VCC2")
		(14 "In6.Cu" signal "L07_GND3")
		(16 "In7.Cu" signal "L08_SIG2")
		(18 "In8.Cu" signal "L09_GND4")
		(2 "B.Cu" signal "BOTTOM")
		(9 "F.Adhes" user "F.Adhesive")
		(11 "B.Adhes" user "B.Adhesive")
		(13 "F.Paste" user "Package Geometry/Pastemask Top")
		(15 "B.Paste" user "Package Geometry/Pastemask Bottom")
		(5 "F.SilkS" user "Ref Des/Silkscreen Top")
		(7 "B.SilkS" user "Ref Des/Silkscreen Bottom")
		(1 "F.Mask" user "Board Geometry/Soldermask Top")
		(3 "B.Mask" user "Board Geometry/Soldermask Bottom")
		(17 "Dwgs.User" user "User.Drawings")
		(19 "Cmts.User" user "User.Comments")
		(21 "Eco1.User" user "User.Eco1")
		(23 "Eco2.User" user "User.Eco2")
		(25 "Edge.Cuts" user "Board Geometry/Outline")
		(27 "Margin" user)
		(31 "F.CrtYd" user "Package Geometry/Place Bound Top")
		(29 "B.CrtYd" user "Package Geometry/Place Bound Bottom")
		(35 "F.Fab" user "Ref Des/Assembly Top")
		(33 "B.Fab" user "Ref Des/Assembly Bottom")
	)
	(footprint ""
		(layer "B.Cu")
		(at 138.049 -107.696 90)
		(property "Reference" "R257"
			(at -5.88137 -0.254 0)
			(unlocked yes)
			(layer "B.SilkS")
			(effects
				(font
					(size 0.7874 0.5842)
					(thickness 0.1524)
				)
				(justify mirror)
			)
		)
		(property "Value" "VAL*"
			(at -0.02032 2.13233 90)
			(unlocked yes)
			(layer "B.Fab")
			(hide yes)
			(effects
				(font
					(size 0.7874 0.5842)
					(thickness 0.1524)
				)
				(justify mirror)
			)
		)
		(property "Device Type" "RESISTOR-G155-13300-01,330OHM,A"
			(at -0.008382 1.210564 90)
			(unlocked yes)
			(layer "B.Fab")
			(hide yes)
			(effects
				(font
					(size 0.7874 0.5842)
					(thickness 0.1524)
				)
				(justify mirror)
			)
		)
		(property "User Part Number" "PARTNUM*"
			(at -0.02032 4.024884 90)
			(unlocked yes)
			(layer "Cmts.User")
			(hide yes)
			(effects
				(font
					(size 0.7874 0.5842)
					(thickness 0.1524)
				)
				(justify mirror)
			)
		)
		(property "Tolerance" "TOL*"
			(at -0.044704 3.05435 90)
			(unlocked yes)
			(layer "Cmts.User")
			(hide yes)
			(effects
				(font
					(size 0.7874 0.5842)
					(thickness 0.1524)
				)
				(justify mirror)
			)
		)
		(duplicate_pad_numbers_are_jumpers no)
		(fp_line
			(start 1.143 -0.5588)
			(end 1.143 0.5588)
			(stroke
				(width 0.1)
				(type default)
			)
			(layer "B.SilkS")
		)
		(fp_line
			(start -1.143 -0.5588)
			(end 1.143 -0.5588)
			(stroke
				(width 0.1)
				(type default)
			)
			(layer "B.SilkS")
		)
		(fp_line
			(start 1.143 0.5588)
			(end -1.143 0.5588)
			(stroke
				(width 0.1)
				(type default)
			)
			(layer "B.SilkS")
		)
		(fp_line
			(start -1.143 0.5588)
			(end -1.143 -0.5588)
			(stroke
				(width 0.1)
				(type default)
			)
			(layer "B.SilkS")
		)
		(fp_rect
			(start -1.143 -0.5588)
			(end 1.143 0.5588)
			(stroke
				(width 0)
				(type default)
			)
			(fill no)
			(layer "B.CrtYd")
		)
		(fp_line
			(start 0.508 -0.3048)
			(end 0.508 0.3048)
			(stroke
				(width 0.1)
				(type default)
			)
			(layer "B.Fab")
		)
		(fp_line
			(start -0.508 -0.3048)
			(end 0.508 -0.3048)
			(stroke
				(width 0.1)
				(type default)
			)
			(layer "B.Fab")
		)
		(fp_line
			(start 0.508 0.3048)
			(end -0.508 0.3048)
			(stroke
				(width 0.1)
				(type default)
			)
			(layer "B.Fab")
		)
		(fp_line
			(start -0.508 0.3048)
			(end -0.508 -0.3048)
			(stroke
				(width 0.1)
				(type default)
			)
			(layer "B.Fab")
		)
		(pad "1" smd rect
			(at 0.5334 0 270)
			(size 0.7112 0.6096)
			(layers "B.Cu" "B.Mask" "B.Paste")
			(net "UNNAMED_14_OPTICAL_I12_A")
		)
		(pad "2" smd rect
			(at -0.5334 0 270)
			(size 0.7112 0.6096)
			(layers "B.Cu" "B.Mask" "B.Paste")
			(net "XP3R3V_FPGA")
		)
		(zone
			(layer "B.Cu")
			(hatch none 0.5)
			(connect_pads
				(clearance 0)
			)
			(min_thickness 0.25)
			(keepout
				(tracks allowed)
				(vias not_allowed)
				(pads allowed)
				(copperpour not_allowed)
				(footprints allowed)
			)
			(placement
				(enabled no)
				(sheetname "")
			)
			(fill
				(thermal_gap 0.5)
				(thermal_bridge_width 0.5)
				(island_removal_mode 0)
			)
			(polygon
				(pts
					(xy 137.7442 -107.6198) (xy 138.3538 -107.6198) (xy 138.3538 -107.7722) (xy 137.7442 -107.7722)
				)
			)
		)
	)
	(footprint ""
		(layer "B.Cu")
		(at 26.416 -91.059 90)
		(property "Reference" "R460"
			(at 2.286 -5.11937 270)
			(unlocked yes)
			(layer "B.SilkS")
			(effects
				(font
					(size 0.7874 0.5842)
					(thickness 0.1524)
				)
				(justify mirror)
			)
		)
		(property "Value" "VAL*"
			(at -0.02032 2.13233 90)
			(unlocked yes)
			(layer "B.Fab")
			(hide yes)
			(effects
				(font
					(size 0.7874 0.5842)
					(thickness 0.1524)
				)
				(justify mirror)
			)
		)
		(property "Tolerance" "TOL*"
			(at -0.044704 3.05435 90)
			(unlocked yes)
			(layer "Cmts.User")
			(hide yes)
			(effects
				(font
					(size 0.7874 0.5842)
					(thickness 0.1524)
				)
				(justify mirror)
			)
		)
		(property "User Part Number" "PARTNUM*"
			(at -0.02032 4.024884 90)
			(unlocked yes)
			(layer "Cmts.User")
			(hide yes)
			(effects
				(font
					(size 0.7874 0.5842)
					(thickness 0.1524)
				)
				(justify mirror)
			)
		)
		(property "Device Type" "RESISTOR-G155-11001-01,1KOHM,1%"
			(at -0.008382 1.210564 90)
			(unlocked yes)
			(layer "B.Fab")
			(hide yes)
			(effects
				(font
					(size 0.7874 0.5842)
					(thickness 0.1524)
				)
				(justify mirror)
			)
		)
		(duplicate_pad_numbers_are_jumpers no)
		(fp_line
			(start 1.143 -0.5588)
			(end 1.143 0.5588)
			(stroke
				(width 0.1)
				(type default)
			)
			(layer "B.SilkS")
		)
		(fp_line
			(start -1.143 -0.5588)
			(end 1.143 -0.5588)
			(stroke
				(width 0.1)
				(type default)
			)
			(layer "B.SilkS")
		)
		(fp_line
			(start 1.143 0.5588)
			(end -1.143 0.5588)
			(stroke
				(width 0.1)
				(type default)
			)
			(layer "B.SilkS")
		)
		(fp_line
			(start -1.143 0.5588)
			(end -1.143 -0.5588)
			(stroke
				(width 0.1)
				(type default)
			)
			(layer "B.SilkS")
		)
		(fp_poly
			(pts
				(xy 1.143 0.5588) (xy -1.143 0.5588) (xy -1.143 -0.5588) (xy 1.143 -0.5588)
			)
			(stroke
				(width 0)
				(type default)
			)
			(fill no)
			(layer "B.CrtYd")
		)
		(fp_line
			(start 0.508 -0.3048)
			(end 0.508 0.3048)
			(stroke
				(width 0.1)
				(type default)
			)
			(layer "B.Fab")
		)
		(fp_line
			(start -0.508 -0.3048)
			(end 0.508 -0.3048)
			(stroke
				(width 0.1)
				(type default)
			)
			(layer "B.Fab")
		)
		(fp_line
			(start 0.508 0.3048)
			(end -0.508 0.3048)
			(stroke
				(width 0.1)
				(type default)
			)
			(layer "B.Fab")
		)
		(fp_line
			(start -0.508 0.3048)
			(end -0.508 -0.3048)
			(stroke
				(width 0.1)
				(type default)
			)
			(layer "B.Fab")
		)
		(pad "1" smd rect
			(at 0.5334 0 270)
			(size 0.7112 0.6096)
			(layers "B.Cu" "B.Mask" "B.Paste")
			(net "FT_USB_DETECT")
		)
		(pad "2" smd rect
			(at -0.5334 0 270)
			(size 0.7112 0.6096)
			(layers "B.Cu" "B.Mask" "B.Paste")
			(net "UNNAMED_524_FT4232HLREELQFP64_7")
		)
		(zone
			(layer "B.Cu")
			(hatch none 0.5)
			(connect_pads
				(clearance 0)
			)
			(min_thickness 0.25)
			(keepout
				(tracks allowed)
				(vias not_allowed)
				(pads allowed)
				(copperpour not_allowed)
				(footprints allowed)
			)
			(placement
				(enabled no)
				(sheetname "")
			)
			(fill
				(thermal_gap 0.5)
				(thermal_bridge_width 0.5)
				(island_removal_mode 0)
			)
			(polygon
				(pts
					(xy 26.7208 -91.1352) (xy 26.1112 -91.1352) (xy 26.1112 -90.9828) (xy 26.7208 -90.9828)
				)
			)
		)
		(zone
			(layer "B.Cu")
			(hatch none 0.5)
			(connect_pads
				(clearance 0)
			)
			(min_thickness 0.25)
			(keepout
				(tracks not_allowed)
				(vias allowed)
				(pads allowed)
				(copperpour not_allowed)
				(footprints allowed)
			)
			(placement
				(enabled no)
				(sheetname "")
			)
			(fill
				(thermal_gap 0.5)
				(thermal_bridge_width 0.5)
				(island_removal_mode 0)
			)
			(polygon
				(pts
					(xy 26.7208 -91.1352) (xy 26.1112 -91.1352) (xy 26.1112 -90.9828) (xy 26.7208 -90.9828)
				)
			)
		)
	)
)
